(kicad_pcb
	(version 20260206)
	(generator "pcbnew")
	(generator_version "10.0")
	(general
		(thickness 1.6)
		(legacy_teardrops no)
	)
	(paper "A4")
	(title_block
		(title "03242023_DA0F0TMBIJ0_F0T_Motherboard_J_brd_V01_OCP.brd")
		(comment 1 "Grand Teton / footprints 867-872 of 6105")
	)
	(layers
		(0 "F.Cu" signal "TOP")
		(4 "In1.Cu" signal "GND")
		(6 "In2.Cu" signal "IN1")
		(8 "In3.Cu" signal "GND1")
		(10 "In4.Cu" signal "IN2")
		(12 "In5.Cu" signal "GND2")
		(14 "In6.Cu" signal "IN3")
		(16 "In7.Cu" signal "GND3")
		(18 "In8.Cu" signal "VCC")
		(20 "In9.Cu" signal "VCC1")
		(22 "In10.Cu" signal "GND4")
		(24 "In11.Cu" signal "IN4")
		(26 "In12.Cu" signal "GND5")
		(28 "In13.Cu" signal "IN5")
		(30 "In14.Cu" signal "GND6")
		(32 "In15.Cu" signal "IN6")
		(34 "In16.Cu" signal "GND7")
		(2 "B.Cu" signal "BOTTOM")
		(9 "F.Adhes" user "F.Adhesive")
		(11 "B.Adhes" user "B.Adhesive")
		(13 "F.Paste" user "Package Geometry/Pastemask Top")
		(15 "B.Paste" user "Package Geometry/Pastemask Bottom")
		(5 "F.SilkS" user "Ref Des/Silkscreen Top")
		(7 "B.SilkS" user "Ref Des/Silkscreen Bottom")
		(1 "F.Mask" user "Board Geometry/Soldermask Top")
		(3 "B.Mask" user "Board Geometry/Soldermask Bottom")
		(17 "Dwgs.User" user "User.Drawings")
		(19 "Cmts.User" user "User.Comments")
		(21 "Eco1.User" user "User.Eco1")
		(23 "Eco2.User" user "User.Eco2")
		(25 "Edge.Cuts" user "Board Geometry/Outline")
		(27 "Margin" user)
		(31 "F.CrtYd" user "Package Geometry/Place Bound Top")
		(29 "B.CrtYd" user "Package Geometry/Place Bound Bottom")
		(35 "F.Fab" user "Ref Des/Assembly Top")
		(33 "B.Fab" user "Ref Des/Assembly Bottom")
	)
	(footprint ""
		(layer "F.Cu")
		(at 349.523304 -336.192368 90)
		(property "Reference" "PC292"
			(at 0 0 90)
			(layer "F.SilkS")
			(hide yes)
			(effects
				(font
					(size 1.27 1.27)
				)
			)
		)
		(property "Value" ""
			(at 0 0 90)
			(layer "F.Fab")
			(effects
				(font
					(size 1.27 1.27)
				)
			)
		)
		(duplicate_pad_numbers_are_jumpers no)
		(fp_line
			(start 0.7874 -0.4064)
			(end 0.7874 0.4064)
			(stroke
				(width 0.1524)
				(type default)
			)
			(layer "F.SilkS")
		)
		(fp_line
			(start -0.7874 -0.4064)
			(end 0.7874 -0.4064)
			(stroke
				(width 0.1524)
				(type default)
			)
			(layer "F.SilkS")
		)
		(fp_line
			(start 0.7874 0.4064)
			(end -0.7874 0.4064)
			(stroke
				(width 0.1524)
				(type default)
			)
			(layer "F.SilkS")
		)
		(fp_line
			(start -0.7874 0.4064)
			(end -0.7874 -0.4064)
			(stroke
				(width 0.1524)
				(type default)
			)
			(layer "F.SilkS")
		)
		(fp_line
			(start -0.12065 -0.305054)
			(end -0.12065 -0.2794)
			(stroke
				(width 0.1)
				(type default)
			)
			(layer "F.Fab")
		)
		(fp_line
			(start -0.67945 -0.305054)
			(end -0.12065 -0.305054)
			(stroke
				(width 0.1)
				(type default)
			)
			(layer "F.Fab")
		)
		(fp_line
			(start 0.67945 -0.3048)
			(end 0.67945 0.3048)
			(stroke
				(width 0.1)
				(type default)
			)
			(layer "F.Fab")
		)
		(fp_line
			(start 0.12065 -0.3048)
			(end 0.67945 -0.3048)
			(stroke
				(width 0.1)
				(type default)
			)
			(layer "F.Fab")
		)
		(fp_line
			(start 0.12065 -0.2794)
			(end 0.12065 -0.3048)
			(stroke
				(width 0.1)
				(type default)
			)
			(layer "F.Fab")
		)
		(fp_line
			(start -0.12065 -0.2794)
			(end 0.12065 -0.2794)
			(stroke
				(width 0.1)
				(type default)
			)
			(layer "F.Fab")
		)
		(fp_line
			(start 0.120396 0.2794)
			(end -0.12065 0.2794)
			(stroke
				(width 0.1)
				(type default)
			)
			(layer "F.Fab")
		)
		(fp_line
			(start -0.12065 0.2794)
			(end -0.12065 0.3048)
			(stroke
				(width 0.1)
				(type default)
			)
			(layer "F.Fab")
		)
		(fp_line
			(start 0.67945 0.3048)
			(end 0.120396 0.3048)
			(stroke
				(width 0.1)
				(type default)
			)
			(layer "F.Fab")
		)
		(fp_line
			(start 0.120396 0.3048)
			(end 0.120396 0.2794)
			(stroke
				(width 0.1)
				(type default)
			)
			(layer "F.Fab")
		)
		(fp_line
			(start -0.12065 0.3048)
			(end -0.67945 0.3048)
			(stroke
				(width 0.1)
				(type default)
			)
			(layer "F.Fab")
		)
		(fp_line
			(start -0.67945 0.3048)
			(end -0.67945 -0.305054)
			(stroke
				(width 0.1)
				(type default)
			)
			(layer "F.Fab")
		)
		(pad "1" smd circle
			(at -0.40005 0 90)
			(size 0 0)
			(layers "F.Cu" "F.Mask" "F.Paste")
			(net "PVCCIN_CPU0_VDD2")
		)
		(pad "2" smd circle
			(at 0.40005 0 90)
			(size 0 0)
			(layers "F.Cu" "F.Mask" "F.Paste")
			(net "GND")
		)
	)
	(footprint ""
		(layer "F.Cu")
		(at 307.899308 -30.255718 -90)
		(property "Reference" "R1307"
			(at 0 0 270)
			(layer "F.SilkS")
			(hide yes)
			(effects
				(font
					(size 1.27 1.27)
				)
			)
		)
		(property "Value" ""
			(at 0 0 270)
			(layer "F.Fab")
			(effects
				(font
					(size 1.27 1.27)
				)
			)
		)
		(duplicate_pad_numbers_are_jumpers no)
		(fp_line
			(start -0.7874 0.4064)
			(end -0.7874 -0.4064)
			(stroke
				(width 0.1524)
				(type default)
			)
			(layer "F.SilkS")
		)
		(fp_line
			(start 0.7874 0.4064)
			(end -0.7874 0.4064)
			(stroke
				(width 0.1524)
				(type default)
			)
			(layer "F.SilkS")
		)
		(fp_line
			(start -0.7874 -0.4064)
			(end 0.7874 -0.4064)
			(stroke
				(width 0.1524)
				(type default)
			)
			(layer "F.SilkS")
		)
		(fp_line
			(start 0.7874 -0.4064)
			(end 0.7874 0.4064)
			(stroke
				(width 0.1524)
				(type default)
			)
			(layer "F.SilkS")
		)
		(fp_line
			(start -0.67945 0.3048)
			(end -0.67945 -0.305054)
			(stroke
				(width 0.1)
				(type default)
			)
			(layer "F.Fab")
		)
		(fp_line
			(start -0.12065 0.3048)
			(end -0.67945 0.3048)
			(stroke
				(width 0.1)
				(type default)
			)
			(layer "F.Fab")
		)
		(fp_line
			(start 0.120396 0.3048)
			(end 0.120396 0.2794)
			(stroke
				(width 0.1)
				(type default)
			)
			(layer "F.Fab")
		)
		(fp_line
			(start 0.67945 0.3048)
			(end 0.120396 0.3048)
			(stroke
				(width 0.1)
				(type default)
			)
			(layer "F.Fab")
		)
		(fp_line
			(start -0.12065 0.2794)
			(end -0.12065 0.3048)
			(stroke
				(width 0.1)
				(type default)
			)
			(layer "F.Fab")
		)
		(fp_line
			(start 0.120396 0.2794)
			(end -0.12065 0.2794)
			(stroke
				(width 0.1)
				(type default)
			)
			(layer "F.Fab")
		)
		(fp_line
			(start -0.12065 -0.2794)
			(end 0.12065 -0.2794)
			(stroke
				(width 0.1)
				(type default)
			)
			(layer "F.Fab")
		)
		(fp_line
			(start 0.12065 -0.2794)
			(end 0.12065 -0.3048)
			(stroke
				(width 0.1)
				(type default)
			)
			(layer "F.Fab")
		)
		(fp_line
			(start 0.12065 -0.3048)
			(end 0.67945 -0.3048)
			(stroke
				(width 0.1)
				(type default)
			)
			(layer "F.Fab")
		)
		(fp_line
			(start 0.67945 -0.3048)
			(end 0.67945 0.3048)
			(stroke
				(width 0.1)
				(type default)
			)
			(layer "F.Fab")
		)
		(fp_line
			(start -0.67945 -0.305054)
			(end -0.12065 -0.305054)
			(stroke
				(width 0.1)
				(type default)
			)
			(layer "F.Fab")
		)
		(fp_line
			(start -0.12065 -0.305054)
			(end -0.12065 -0.2794)
			(stroke
				(width 0.1)
				(type default)
			)
			(layer "F.Fab")
		)
		(pad "1" smd circle
			(at -0.40005 0 270)
			(size 0 0)
			(layers "F.Cu" "F.Mask" "F.Paste")
			(net "FM_THROTTLE_N")
		)
		(pad "2" smd circle
			(at 0.40005 0 270)
			(size 0 0)
			(layers "F.Cu" "F.Mask" "F.Paste")
			(net "FM_THROTTLE_R_N")
		)
	)
	(footprint ""
		(layer "F.Cu")
		(at 113.67008 -122.132598 90)
		(property "Reference" "R4039"
			(at 0 0 90)
			(layer "F.SilkS")
			(hide yes)
			(effects
				(font
					(size 1.27 1.27)
				)
			)
		)
		(property "Value" ""
			(at 0 0 90)
			(layer "F.Fab")
			(effects
				(font
					(size 1.27 1.27)
				)
			)
		)
		(duplicate_pad_numbers_are_jumpers no)
		(fp_line
			(start 0.7874 -0.4064)
			(end 0.7874 0.4064)
			(stroke
				(width 0.1524)
				(type default)
			)
			(layer "F.SilkS")
		)
		(fp_line
			(start -0.7874 -0.4064)
			(end 0.7874 -0.4064)
			(stroke
				(width 0.1524)
				(type default)
			)
			(layer "F.SilkS")
		)
		(fp_line
			(start 0.7874 0.4064)
			(end -0.7874 0.4064)
			(stroke
				(width 0.1524)
				(type default)
			)
			(layer "F.SilkS")
		)
		(fp_line
			(start -0.7874 0.4064)
			(end -0.7874 -0.4064)
			(stroke
				(width 0.1524)
				(type default)
			)
			(layer "F.SilkS")
		)
		(fp_line
			(start -0.12065 -0.305054)
			(end -0.12065 -0.2794)
			(stroke
				(width 0.1)
				(type default)
			)
			(layer "F.Fab")
		)
		(fp_line
			(start -0.67945 -0.305054)
			(end -0.12065 -0.305054)
			(stroke
				(width 0.1)
				(type default)
			)
			(layer "F.Fab")
		)
		(fp_line
			(start 0.67945 -0.3048)
			(end 0.67945 0.3048)
			(stroke
				(width 0.1)
				(type default)
			)
			(layer "F.Fab")
		)
		(fp_line
			(start 0.12065 -0.3048)
			(end 0.67945 -0.3048)
			(stroke
				(width 0.1)
				(type default)
			)
			(layer "F.Fab")
		)
		(fp_line
			(start 0.12065 -0.2794)
			(end 0.12065 -0.3048)
			(stroke
				(width 0.1)
				(type default)
			)
			(layer "F.Fab")
		)
		(fp_line
			(start -0.12065 -0.2794)
			(end 0.12065 -0.2794)
			(stroke
				(width 0.1)
				(type default)
			)
			(layer "F.Fab")
		)
		(fp_line
			(start 0.120396 0.2794)
			(end -0.12065 0.2794)
			(stroke
				(width 0.1)
				(type default)
			)
			(layer "F.Fab")
		)
		(fp_line
			(start -0.12065 0.2794)
			(end -0.12065 0.3048)
			(stroke
				(width 0.1)
				(type default)
			)
			(layer "F.Fab")
		)
		(fp_line
			(start 0.67945 0.3048)
			(end 0.120396 0.3048)
			(stroke
				(width 0.1)
				(type default)
			)
			(layer "F.Fab")
		)
		(fp_line
			(start 0.120396 0.3048)
			(end 0.120396 0.2794)
			(stroke
				(width 0.1)
				(type default)
			)
			(layer "F.Fab")
		)
		(fp_line
			(start -0.12065 0.3048)
			(end -0.67945 0.3048)
			(stroke
				(width 0.1)
				(type default)
			)
			(layer "F.Fab")
		)
		(fp_line
			(start -0.67945 0.3048)
			(end -0.67945 -0.305054)
			(stroke
				(width 0.1)
				(type default)
			)
			(layer "F.Fab")
		)
		(pad "1" smd circle
			(at -0.40005 0 90)
			(size 0 0)
			(layers "F.Cu" "F.Mask" "F.Paste")
			(net "P0V62_CPU0_RST_DDR_VREF")
		)
		(pad "2" smd circle
			(at 0.40005 0 90)
			(size 0 0)
			(layers "F.Cu" "F.Mask" "F.Paste")
			(net "GND")
		)
	)
	(footprint ""
		(layer "F.Cu")
		(at 131.6736 -125.758448 180)
		(property "Reference" "R3152"
			(at 0 0 180)
			(layer "F.SilkS")
			(hide yes)
			(effects
				(font
					(size 1.27 1.27)
				)
			)
		)
		(property "Value" ""
			(at 0 0 180)
			(layer "F.Fab")
			(effects
				(font
					(size 1.27 1.27)
				)
			)
		)
		(duplicate_pad_numbers_are_jumpers no)
		(fp_line
			(start 0.7874 0.4064)
			(end -0.7874 0.4064)
			(stroke
				(width 0.1524)
				(type default)
			)
			(layer "F.SilkS")
		)
		(fp_line
			(start 0.7874 -0.4064)
			(end 0.7874 0.4064)
			(stroke
				(width 0.1524)
				(type default)
			)
			(layer "F.SilkS")
		)
		(fp_line
			(start -0.7874 0.4064)
			(end -0.7874 -0.4064)
			(stroke
				(width 0.1524)
				(type default)
			)
			(layer "F.SilkS")
		)
		(fp_line
			(start -0.7874 -0.4064)
			(end 0.7874 -0.4064)
			(stroke
				(width 0.1524)
				(type default)
			)
			(layer "F.SilkS")
		)
		(fp_line
			(start 0.67945 0.3048)
			(end 0.120396 0.3048)
			(stroke
				(width 0.1)
				(type default)
			)
			(layer "F.Fab")
		)
		(fp_line
			(start 0.67945 -0.3048)
			(end 0.67945 0.3048)
			(stroke
				(width 0.1)
				(type default)
			)
			(layer "F.Fab")
		)
		(fp_line
			(start 0.12065 -0.2794)
			(end 0.12065 -0.3048)
			(stroke
				(width 0.1)
				(type default)
			)
			(layer "F.Fab")
		)
		(fp_line
			(start 0.12065 -0.3048)
			(end 0.67945 -0.3048)
			(stroke
				(width 0.1)
				(type default)
			)
			(layer "F.Fab")
		)
		(fp_line
			(start 0.120396 0.3048)
			(end 0.120396 0.2794)
			(stroke
				(width 0.1)
				(type default)
			)
			(layer "F.Fab")
		)
		(fp_line
			(start 0.120396 0.2794)
			(end -0.12065 0.2794)
			(stroke
				(width 0.1)
				(type default)
			)
			(layer "F.Fab")
		)
		(fp_line
			(start -0.12065 0.3048)
			(end -0.67945 0.3048)
			(stroke
				(width 0.1)
				(type default)
			)
			(layer "F.Fab")
		)
		(fp_line
			(start -0.12065 0.2794)
			(end -0.12065 0.3048)
			(stroke
				(width 0.1)
				(type default)
			)
			(layer "F.Fab")
		)
		(fp_line
			(start -0.12065 -0.2794)
			(end 0.12065 -0.2794)
			(stroke
				(width 0.1)
				(type default)
			)
			(layer "F.Fab")
		)
		(fp_line
			(start -0.12065 -0.305054)
			(end -0.12065 -0.2794)
			(stroke
				(width 0.1)
				(type default)
			)
			(layer "F.Fab")
		)
		(fp_line
			(start -0.67945 0.3048)
			(end -0.67945 -0.305054)
			(stroke
				(width 0.1)
				(type default)
			)
			(layer "F.Fab")
		)
		(fp_line
			(start -0.67945 -0.305054)
			(end -0.12065 -0.305054)
			(stroke
				(width 0.1)
				(type default)
			)
			(layer "F.Fab")
		)
		(pad "1" smd circle
			(at -0.40005 0 180)
			(size 0 0)
			(layers "F.Cu" "F.Mask" "F.Paste")
			(net "PD_SMB_OCP2_HP_ADD1")
		)
		(pad "2" smd circle
			(at 0.40005 0 180)
			(size 0 0)
			(layers "F.Cu" "F.Mask" "F.Paste")
			(net "GND")
		)
	)
	(footprint ""
		(layer "F.Cu")
		(at 114.706654 -359.94975)
		(property "Reference" "PC547"
			(at 0 0 0)
			(layer "F.SilkS")
			(hide yes)
			(effects
				(font
					(size 1.27 1.27)
				)
			)
		)
		(property "Value" ""
			(at 0 0 0)
			(layer "F.Fab")
			(effects
				(font
					(size 1.27 1.27)
				)
			)
		)
		(duplicate_pad_numbers_are_jumpers no)
		(fp_line
			(start -0.7874 -0.4064)
			(end 0.7874 -0.4064)
			(stroke
				(width 0.1524)
				(type default)
			)
			(layer "F.SilkS")
		)
		(fp_line
			(start -0.7874 0.4064)
			(end -0.7874 -0.4064)
			(stroke
				(width 0.1524)
				(type default)
			)
			(layer "F.SilkS")
		)
		(fp_line
			(start 0.7874 -0.4064)
			(end 0.7874 0.4064)
			(stroke
				(width 0.1524)
				(type default)
			)
			(layer "F.SilkS")
		)
		(fp_line
			(start 0.7874 0.4064)
			(end -0.7874 0.4064)
			(stroke
				(width 0.1524)
				(type default)
			)
			(layer "F.SilkS")
		)
		(fp_line
			(start -0.67945 -0.305054)
			(end -0.12065 -0.305054)
			(stroke
				(width 0.1)
				(type default)
			)
			(layer "F.Fab")
		)
		(fp_line
			(start -0.67945 0.3048)
			(end -0.67945 -0.305054)
			(stroke
				(width 0.1)
				(type default)
			)
			(layer "F.Fab")
		)
		(fp_line
			(start -0.12065 -0.305054)
			(end -0.12065 -0.2794)
			(stroke
				(width 0.1)
				(type default)
			)
			(layer "F.Fab")
		)
		(fp_line
			(start -0.12065 -0.2794)
			(end 0.12065 -0.2794)
			(stroke
				(width 0.1)
				(type default)
			)
			(layer "F.Fab")
		)
		(fp_line
			(start -0.12065 0.2794)
			(end -0.12065 0.3048)
			(stroke
				(width 0.1)
				(type default)
			)
			(layer "F.Fab")
		)
		(fp_line
			(start -0.12065 0.3048)
			(end -0.67945 0.3048)
			(stroke
				(width 0.1)
				(type default)
			)
			(layer "F.Fab")
		)
		(fp_line
			(start 0.120396 0.2794)
			(end -0.12065 0.2794)
			(stroke
				(width 0.1)
				(type default)
			)
			(layer "F.Fab")
		)
		(fp_line
			(start 0.120396 0.3048)
			(end 0.120396 0.2794)
			(stroke
				(width 0.1)
				(type default)
			)
			(layer "F.Fab")
		)
		(fp_line
			(start 0.12065 -0.3048)
			(end 0.67945 -0.3048)
			(stroke
				(width 0.1)
				(type default)
			)
			(layer "F.Fab")
		)
		(fp_line
			(start 0.12065 -0.2794)
			(end 0.12065 -0.3048)
			(stroke
				(width 0.1)
				(type default)
			)
			(layer "F.Fab")
		)
		(fp_line
			(start 0.67945 -0.3048)
			(end 0.67945 0.3048)
			(stroke
				(width 0.1)
				(type default)
			)
			(layer "F.Fab")
		)
		(fp_line
			(start 0.67945 0.3048)
			(end 0.120396 0.3048)
			(stroke
				(width 0.1)
				(type default)
			)
			(layer "F.Fab")
		)
		(pad "1" smd circle
			(at -0.40005 0)
			(size 0 0)
			(layers "F.Cu" "F.Mask" "F.Paste")
			(net "PVCCIN_CPU1_CSPIN")
		)
		(pad "2" smd circle
			(at 0.40005 0)
			(size 0 0)
			(layers "F.Cu" "F.Mask" "F.Paste")
			(net "GND")
		)
	)
	(footprint ""
		(layer "F.Cu")
		(at 440.383676 -15.656306 180)
		(property "Reference" "C1233"
			(at 0 0 180)
			(layer "F.SilkS")
			(hide yes)
			(effects
				(font
					(size 1.27 1.27)
				)
			)
		)
		(property "Value" ""
			(at 0 0 180)
			(layer "F.Fab")
			(effects
				(font
					(size 1.27 1.27)
				)
			)
		)
		(duplicate_pad_numbers_are_jumpers no)
		(fp_line
			(start 0.7874 0.4064)
			(end -0.7874 0.4064)
			(stroke
				(width 0.1524)
				(type default)
			)
			(layer "F.SilkS")
		)
		(fp_line
			(start 0.7874 -0.4064)
			(end 0.7874 0.4064)
			(stroke
				(width 0.1524)
				(type default)
			)
			(layer "F.SilkS")
		)
		(fp_line
			(start -0.7874 0.4064)
			(end -0.7874 -0.4064)
			(stroke
				(width 0.1524)
				(type default)
			)
			(layer "F.SilkS")
		)
		(fp_line
			(start -0.7874 -0.4064)
			(end 0.7874 -0.4064)
			(stroke
				(width 0.1524)
				(type default)
			)
			(layer "F.SilkS")
		)
		(fp_line
			(start 0.67945 0.3048)
			(end 0.120396 0.3048)
			(stroke
				(width 0.1)
				(type default)
			)
			(layer "F.Fab")
		)
		(fp_line
			(start 0.67945 -0.3048)
			(end 0.67945 0.3048)
			(stroke
				(width 0.1)
				(type default)
			)
			(layer "F.Fab")
		)
		(fp_line
			(start 0.12065 -0.2794)
			(end 0.12065 -0.3048)
			(stroke
				(width 0.1)
				(type default)
			)
			(layer "F.Fab")
		)
		(fp_line
			(start 0.12065 -0.3048)
			(end 0.67945 -0.3048)
			(stroke
				(width 0.1)
				(type default)
			)
			(layer "F.Fab")
		)
		(fp_line
			(start 0.120396 0.3048)
			(end 0.120396 0.2794)
			(stroke
				(width 0.1)
				(type default)
			)
			(layer "F.Fab")
		)
		(fp_line
			(start 0.120396 0.2794)
			(end -0.12065 0.2794)
			(stroke
				(width 0.1)
				(type default)
			)
			(layer "F.Fab")
		)
		(fp_line
			(start -0.12065 0.3048)
			(end -0.67945 0.3048)
			(stroke
				(width 0.1)
				(type default)
			)
			(layer "F.Fab")
		)
		(fp_line
			(start -0.12065 0.2794)
			(end -0.12065 0.3048)
			(stroke
				(width 0.1)
				(type default)
			)
			(layer "F.Fab")
		)
		(fp_line
			(start -0.12065 -0.2794)
			(end 0.12065 -0.2794)
			(stroke
				(width 0.1)
				(type default)
			)
			(layer "F.Fab")
		)
		(fp_line
			(start -0.12065 -0.305054)
			(end -0.12065 -0.2794)
			(stroke
				(width 0.1)
				(type default)
			)
			(layer "F.Fab")
		)
		(fp_line
			(start -0.67945 0.3048)
			(end -0.67945 -0.305054)
			(stroke
				(width 0.1)
				(type default)
			)
			(layer "F.Fab")
		)
		(fp_line
			(start -0.67945 -0.305054)
			(end -0.12065 -0.305054)
			(stroke
				(width 0.1)
				(type default)
			)
			(layer "F.Fab")
		)
		(pad "1" smd circle
			(at -0.40005 0 180)
			(size 0 0)
			(layers "F.Cu" "F.Mask" "F.Paste")
			(net "P12V_OCP_SFF")
		)
		(pad "2" smd circle
			(at 0.40005 0 180)
			(size 0 0)
			(layers "F.Cu" "F.Mask" "F.Paste")
			(net "GND")
		)
	)
)
